FILE_TYPE = CONNECTIVITY;
{Allegro Design Entry HDL 16.6-p007 (v16-6-112F) 10/10/2012}
"PAGE_NUMBER" = 9;
0"NC";
END.
